(kicad_pcb
	(version 20241229)
	(generator "pcbnew")
	(generator_version "9.0")
	(general
		(thickness 1.711)
		(legacy_teardrops no)
	)
	(paper "A4")
	(title_block
		(title "Antmicro Baseboard for Jetson AGX Thor")
		(date "2026-02-18")
		(rev "1.1.0")
		(company "Antmicro Ltd")
		(comment 1 "www.antmicro.com")
		(comment 9 "footprints 910-914 of 1170")
	)
	(layers
		(0 "F.Cu" signal)
		(4 "In1.Cu" signal)
		(6 "In2.Cu" signal)
		(8 "In3.Cu" signal)
		(10 "In4.Cu" jumper)
		(12 "In5.Cu" signal)
		(14 "In6.Cu" signal)
		(16 "In7.Cu" signal)
		(18 "In8.Cu" signal)
		(2 "B.Cu" signal)
		(9 "F.Adhes" user "F.Adhesive")
		(11 "B.Adhes" user "B.Adhesive")
		(13 "F.Paste" user)
		(15 "B.Paste" user)
		(5 "F.SilkS" user "F.Silkscreen")
		(7 "B.SilkS" user "B.Silkscreen")
		(1 "F.Mask" user)
		(3 "B.Mask" user)
		(17 "Dwgs.User" user "User.Drawings")
		(19 "Cmts.User" user "User.Comments")
		(21 "Eco1.User" user "User.Eco1")
		(23 "Eco2.User" user "User.Eco2")
		(25 "Edge.Cuts" user)
		(27 "Margin" user)
		(31 "F.CrtYd" user "F.Courtyard")
		(29 "B.CrtYd" user "B.Courtyard")
		(35 "F.Fab" user)
		(33 "B.Fab" user)
	)
	(footprint "antmicro-footprints:R_0402_1005Metric"
		(layer "B.Cu")
		(at 197 87.8 90)
		(descr "Resistor SMD 0402")
		(tags "resistor SMD 0402")
		(property "Reference" "R381"
			(at -3.7 -0.4 90)
			(layer "B.SilkS")
			(effects
				(font
					(size 0.7 0.7)
					(thickness 0.15)
				)
				(justify right top mirror)
			)
		)
		(property "Value" "R_0R_0402"
			(at -1.011843 -1.772047 90)
			(layer "B.Fab")
			(effects
				(font
					(size 0.7 0.7)
					(thickness 0.15)
				)
				(justify right top mirror)
			)
		)
		(property "Datasheet" "https://industrial.panasonic.com/cdbs/www-data/pdf/RDA0000/AOA0000C301.pdf"
			(at 0 0 90)
			(layer "B.Fab")
			(hide yes)
			(effects
				(font
					(size 1.27 1.27)
					(thickness 0.15)
				)
				(justify mirror)
			)
		)
		(property "Description" "SMD Chip Resistor, Jumper, 0 ohm, 100 mW, 0402 [1005 Metric], Thick Film, General Purpose"
			(at 0 0 90)
			(layer "B.Fab")
			(hide yes)
			(effects
				(font
					(size 1.27 1.27)
					(thickness 0.15)
				)
				(justify mirror)
			)
		)
		(property "MPN" "ERJ2GE0R00X"
			(at 0 0 270)
			(unlocked yes)
			(layer "B.Fab")
			(hide yes)
			(effects
				(font
					(size 1 1)
					(thickness 0.15)
				)
				(justify mirror)
			)
		)
		(property "Manufacturer" "Panasonic"
			(at 0 0 270)
			(unlocked yes)
			(layer "B.Fab")
			(hide yes)
			(effects
				(font
					(size 1 1)
					(thickness 0.15)
				)
				(justify mirror)
			)
		)
		(property "License" "Apache-2.0"
			(at 0 0 270)
			(unlocked yes)
			(layer "B.Fab")
			(hide yes)
			(effects
				(font
					(size 1 1)
					(thickness 0.15)
				)
				(justify mirror)
			)
		)
		(property "Author" "Antmicro"
			(at 0 0 270)
			(unlocked yes)
			(layer "B.Fab")
			(hide yes)
			(effects
				(font
					(size 1 1)
					(thickness 0.15)
				)
				(justify mirror)
			)
		)
		(property "Val" "0R"
			(at 0 0 270)
			(unlocked yes)
			(layer "B.Fab")
			(hide yes)
			(effects
				(font
					(size 1 1)
					(thickness 0.15)
				)
				(justify mirror)
			)
		)
		(property "Tolerance" "~"
			(at 0 0 270)
			(unlocked yes)
			(layer "B.Fab")
			(hide yes)
			(effects
				(font
					(size 1 1)
					(thickness 0.15)
				)
				(justify mirror)
			)
		)
		(property "Current" "1A"
			(at 0 0 270)
			(unlocked yes)
			(layer "B.Fab")
			(hide yes)
			(effects
				(font
					(size 1 1)
					(thickness 0.15)
				)
				(justify mirror)
			)
		)
		(sheetname "/USB Debug, PD/")
		(sheetfile "usb_debug_pd.kicad_sch")
		(attr smd)
		(fp_rect
			(start -0.925 0.47)
			(end 0.925 -0.47)
			(stroke
				(width 0.05)
				(type default)
			)
			(fill no)
			(layer "B.CrtYd")
		)
		(fp_rect
			(start -0.5 0.25)
			(end 0.5 -0.25)
			(stroke
				(width 0.15)
				(type solid)
			)
			(fill no)
			(layer "B.Fab")
		)
		(fp_text user "${REFERENCE}"
			(at -0.95 -3.168 90)
			(layer "B.Fab")
			(effects
				(font
					(size 0.7 0.7)
					(thickness 0.15)
				)
				(justify right top mirror)
			)
		)
		(fp_text user "Author: Antmicro"
			(at -0.95 -4.169 90)
			(layer "B.Fab")
			(effects
				(font
					(size 0.7 0.7)
					(thickness 0.15)
				)
				(justify right top mirror)
			)
		)
		(fp_text user "License: Apache-2.0"
			(at -0.95 -5.169 90)
			(layer "B.Fab")
			(effects
				(font
					(size 0.7 0.7)
					(thickness 0.15)
				)
				(justify right top mirror)
			)
		)
		(pad "1" smd roundrect
			(at -0.48 0 90)
			(size 0.59 0.64)
			(layers "B.Cu" "B.Mask" "B.Paste")
			(roundrect_rratio 0.25)
			(net 812 "/USB Debug, PD/~{CS}")
			(pintype "passive")
		)
		(pad "2" smd roundrect
			(at 0.48 0 90)
			(size 0.59 0.64)
			(layers "B.Cu" "B.Mask" "B.Paste")
			(roundrect_rratio 0.25)
			(net 939 "/USB Debug, PD/~{PDC_CS}")
			(pintype "passive")
		)
	)
	(footprint "antmicro-footprints:R_0402_1005Metric"
		(layer "B.Cu")
		(at 235.694 108.825 180)
		(descr "Resistor SMD 0402")
		(tags "resistor SMD 0402")
		(property "Reference" "R270"
			(at 0.094 -4.475 0)
			(layer "B.SilkS")
			(effects
				(font
					(size 0.7 0.7)
					(thickness 0.15)
				)
				(justify left bottom mirror)
			)
		)
		(property "Value" "R_2k2_0402"
			(at -1.011843 -1.772046 0)
			(layer "B.Fab")
			(effects
				(font
					(size 0.7 0.7)
					(thickness 0.15)
				)
				(justify left bottom mirror)
			)
		)
		(property "Datasheet" "https://www.bourns.com/docs/product-datasheets/cr.pdf"
			(at 0 0 0)
			(layer "B.Fab")
			(hide yes)
			(effects
				(font
					(size 1.27 1.27)
					(thickness 0.15)
				)
				(justify mirror)
			)
		)
		(property "Description" "SMD Chip Resistor, 2.2 kohm, ± 1%, 62.5 mW, 0402 [1005 Metric], Thick Film, General Purpose"
			(at 0 0 0)
			(layer "B.Fab")
			(hide yes)
			(effects
				(font
					(size 1.27 1.27)
					(thickness 0.15)
				)
				(justify mirror)
			)
		)
		(property "Manufacturer" "Bourns"
			(at 0 0 0)
			(unlocked yes)
			(layer "B.Fab")
			(hide yes)
			(effects
				(font
					(size 1 1)
					(thickness 0.15)
				)
				(justify mirror)
			)
		)
		(property "MPN" "CR0402-FX-2201GLF"
			(at 0 0 0)
			(unlocked yes)
			(layer "B.Fab")
			(hide yes)
			(effects
				(font
					(size 1 1)
					(thickness 0.15)
				)
				(justify mirror)
			)
		)
		(property "Val" "2k2"
			(at 0 0 0)
			(unlocked yes)
			(layer "B.Fab")
			(hide yes)
			(effects
				(font
					(size 1 1)
					(thickness 0.15)
				)
				(justify mirror)
			)
		)
		(property "License" "Apache-2.0"
			(at 0 0 0)
			(unlocked yes)
			(layer "B.Fab")
			(hide yes)
			(effects
				(font
					(size 1 1)
					(thickness 0.15)
				)
				(justify mirror)
			)
		)
		(property "Author" "Antmicro"
			(at 0 0 0)
			(unlocked yes)
			(layer "B.Fab")
			(hide yes)
			(effects
				(font
					(size 1 1)
					(thickness 0.15)
				)
				(justify mirror)
			)
		)
		(property "Tolerance" "1%"
			(at 0 0 0)
			(unlocked yes)
			(layer "B.Fab")
			(hide yes)
			(effects
				(font
					(size 1 1)
					(thickness 0.15)
				)
				(justify mirror)
			)
		)
		(sheetname "/Recovery USB/")
		(sheetfile "recovery_usb.kicad_sch")
		(attr smd)
		(fp_poly
			(pts
				(xy -0.925 0.47) (xy -0.925 -0.47) (xy 0.925 -0.47) (xy 0.925 0.47)
			)
			(stroke
				(width 0.05)
				(type default)
			)
			(fill no)
			(layer "B.CrtYd")
		)
		(fp_poly
			(pts
				(xy -0.5 0.25) (xy -0.5 -0.25) (xy 0.5 -0.25) (xy 0.5 0.25)
			)
			(stroke
				(width 0.15)
				(type solid)
			)
			(fill no)
			(layer "B.Fab")
		)
		(fp_text user "License: Apache-2.0"
			(at -0.949999 -5.169 0)
			(layer "B.Fab")
			(effects
				(font
					(size 0.7 0.7)
					(thickness 0.15)
				)
				(justify left bottom mirror)
			)
		)
		(fp_text user "Author: Antmicro"
			(at -0.95 -4.169 0)
			(layer "B.Fab")
			(effects
				(font
					(size 0.7 0.7)
					(thickness 0.15)
				)
				(justify left bottom mirror)
			)
		)
		(fp_text user "${REFERENCE}"
			(at -0.95 -3.168 0)
			(layer "B.Fab")
			(effects
				(font
					(size 0.7 0.7)
					(thickness 0.15)
				)
				(justify left bottom mirror)
			)
		)
		(pad "1" smd roundrect
			(at -0.48 0 180)
			(size 0.59 0.64)
			(layers "B.Cu" "B.Mask" "B.Paste")
			(roundrect_rratio 0.25)
			(net 1 "GND")
			(pintype "passive")
		)
		(pad "2" smd roundrect
			(at 0.48 0 180)
			(size 0.59 0.64)
			(layers "B.Cu" "B.Mask" "B.Paste")
			(roundrect_rratio 0.25)
			(net 1020 "/Recovery USB/USBC2_ISET")
			(pintype "passive")
		)
	)
	(footprint "antmicro-footprints:TP_SMD_0.75mm"
		(layer "B.Cu")
		(at 85.25 58.55 180)
		(property "Reference" "TP120"
			(at 0.56 -0.44 180)
			(layer "B.SilkS")
			(effects
				(font
					(size 0.7 0.7)
					(thickness 0.15)
				)
				(justify left bottom mirror)
			)
		)
		(property "Value" "TP_0.75mm_SMD"
			(at 0 -1.2 0)
			(layer "B.Fab")
			(effects
				(font
					(size 0.7 0.7)
					(thickness 0.15)
				)
				(justify left bottom mirror)
			)
		)
		(property "Description" "SMT test point"
			(at 0 0 0)
			(layer "B.Fab")
			(hide yes)
			(effects
				(font
					(size 1.27 1.27)
					(thickness 0.15)
				)
				(justify mirror)
			)
		)
		(property "MPN" ""
			(at 0 0 0)
			(unlocked yes)
			(layer "B.Fab")
			(hide yes)
			(effects
				(font
					(size 1 1)
					(thickness 0.15)
				)
				(justify mirror)
			)
		)
		(property "Manufacturer" ""
			(at 0 0 0)
			(unlocked yes)
			(layer "B.Fab")
			(hide yes)
			(effects
				(font
					(size 1 1)
					(thickness 0.15)
				)
				(justify mirror)
			)
		)
		(property "Author" "Antmicro"
			(at 0 0 0)
			(unlocked yes)
			(layer "B.Fab")
			(hide yes)
			(effects
				(font
					(size 1 1)
					(thickness 0.15)
				)
				(justify mirror)
			)
		)
		(property "License" "Apache-2.0"
			(at 0 0 0)
			(unlocked yes)
			(layer "B.Fab")
			(hide yes)
			(effects
				(font
					(size 1 1)
					(thickness 0.15)
				)
				(justify mirror)
			)
		)
		(sheetname "/SoM_Power/")
		(sheetfile "som_power.kicad_sch")
		(attr exclude_from_pos_files exclude_from_bom)
		(fp_circle
			(center 0 0)
			(end 0.475 0)
			(stroke
				(width 0.05)
				(type default)
			)
			(fill no)
			(layer "B.CrtYd")
		)
		(fp_text user "Author: Antmicro"
			(at -0.4 -3.901 0)
			(layer "B.Fab")
			(effects
				(font
					(size 0.7 0.7)
					(thickness 0.15)
				)
				(justify left bottom mirror)
			)
		)
		(fp_text user "${REFERENCE}"
			(at -0.4 -2.7 0)
			(layer "B.Fab")
			(effects
				(font
					(size 0.7 0.7)
					(thickness 0.15)
				)
				(justify left bottom mirror)
			)
		)
		(fp_text user "License: Apache-2.0"
			(at -0.4 -5.101 0)
			(layer "B.Fab")
			(effects
				(font
					(size 0.7 0.7)
					(thickness 0.15)
				)
				(justify left bottom mirror)
			)
		)
		(pad "1" smd circle
			(at 0 0 180)
			(size 0.75 0.75)
			(layers "B.Cu" "B.Mask")
			(net 1382 "Net-(R300-Pad2)")
			(pinfunction "1")
			(pintype "passive")
		)
	)
	(footprint "antmicro-footprints:C_0402_1005Metric"
		(layer "B.Cu")
		(at 215.026 152.2 180)
		(descr "Capacitor SMD 0402")
		(tags "capacitor SMD 0402")
		(property "Reference" "C175"
			(at -1.6 0.81 0)
			(layer "B.SilkS")
			(effects
				(font
					(size 0.7 0.7)
					(thickness 0.15)
				)
				(justify left bottom mirror)
			)
		)
		(property "Value" "C_100n_0402"
			(at -1.022927 -2.155213 0)
			(layer "B.Fab")
			(effects
				(font
					(size 0.7 0.7)
					(thickness 0.15)
				)
				(justify left bottom mirror)
			)
		)
		(property "Datasheet" "https://www.murata.com/products/productdetail?partno=GRM155R61H104KE14%23"
			(at 0 0 0)
			(layer "B.Fab")
			(hide yes)
			(effects
				(font
					(size 1.27 1.27)
					(thickness 0.15)
				)
				(justify mirror)
			)
		)
		(property "Description" "SMD Multilayer Ceramic Capacitor, 0.1 µF, 50 V, 0402 [1005 Metric], ± 10%, X5R, GRM Series"
			(at 0 0 0)
			(layer "B.Fab")
			(hide yes)
			(effects
				(font
					(size 1.27 1.27)
					(thickness 0.15)
				)
				(justify mirror)
			)
		)
		(property "MPN" "GRM155R61H104KE14D"
			(at 0 0 0)
			(unlocked yes)
			(layer "B.Fab")
			(hide yes)
			(effects
				(font
					(size 1 1)
					(thickness 0.15)
				)
				(justify mirror)
			)
		)
		(property "Manufacturer" "Murata"
			(at 0 0 0)
			(unlocked yes)
			(layer "B.Fab")
			(hide yes)
			(effects
				(font
					(size 1 1)
					(thickness 0.15)
				)
				(justify mirror)
			)
		)
		(property "License" "Apache-2.0"
			(at 0 0 0)
			(unlocked yes)
			(layer "B.Fab")
			(hide yes)
			(effects
				(font
					(size 1 1)
					(thickness 0.15)
				)
				(justify mirror)
			)
		)
		(property "Author" "Antmicro"
			(at 0 0 0)
			(unlocked yes)
			(layer "B.Fab")
			(hide yes)
			(effects
				(font
					(size 1 1)
					(thickness 0.15)
				)
				(justify mirror)
			)
		)
		(property "Val" "100n"
			(at 0 0 0)
			(unlocked yes)
			(layer "B.Fab")
			(hide yes)
			(effects
				(font
					(size 1 1)
					(thickness 0.15)
				)
				(justify mirror)
			)
		)
		(property "Voltage" "50V"
			(at 0 0 0)
			(unlocked yes)
			(layer "B.Fab")
			(hide yes)
			(effects
				(font
					(size 1 1)
					(thickness 0.15)
				)
				(justify mirror)
			)
		)
		(property "Dielectric" "X5R"
			(at 0 0 0)
			(unlocked yes)
			(layer "B.Fab")
			(hide yes)
			(effects
				(font
					(size 1 1)
					(thickness 0.15)
				)
				(justify mirror)
			)
		)
		(sheetname "/SFP/")
		(sheetfile "sfp.kicad_sch")
		(attr smd)
		(fp_poly
			(pts
				(xy -0.925 0.47) (xy -0.925 -0.47) (xy 0.925 -0.47) (xy 0.925 0.47)
			)
			(stroke
				(width 0.05)
				(type default)
			)
			(fill no)
			(layer "B.CrtYd")
		)
		(fp_line
			(start 0.504 0.25)
			(end 0.504 -0.248)
			(stroke
				(width 0.15)
				(type solid)
			)
			(layer "B.Fab")
		)
		(fp_line
			(start 0.504 -0.248)
			(end -0.494 -0.248)
			(stroke
				(width 0.15)
				(type solid)
			)
			(layer "B.Fab")
		)
		(fp_line
			(start -0.494 0.25)
			(end 0.504 0.25)
			(stroke
				(width 0.15)
				(type solid)
			)
			(layer "B.Fab")
		)
		(fp_line
			(start -0.494 -0.248)
			(end -0.494 0.25)
			(stroke
				(width 0.15)
				(type solid)
			)
			(layer "B.Fab")
		)
		(fp_text user "License: Apache-2.0"
			(at -0.939 -5.799 0)
			(layer "B.Fab")
			(effects
				(font
					(size 0.7 0.7)
					(thickness 0.15)
				)
				(justify left bottom mirror)
			)
		)
		(fp_text user "${REFERENCE}"
			(at -0.939 -4.599 0)
			(layer "B.Fab")
			(effects
				(font
					(size 0.7 0.7)
					(thickness 0.15)
				)
				(justify left bottom mirror)
			)
		)
		(fp_text user "Author: Antmicro"
			(at -0.939 -3.399 0)
			(layer "B.Fab")
			(effects
				(font
					(size 0.7 0.7)
					(thickness 0.15)
				)
				(justify left bottom mirror)
			)
		)
		(pad "1" smd roundrect
			(at -0.48 0 180)
			(size 0.59 0.64)
			(layers "B.Cu" "B.Mask" "B.Paste")
			(roundrect_rratio 0.25)
			(net 1 "GND")
			(pintype "passive")
		)
		(pad "2" smd roundrect
			(at 0.48 0 180)
			(size 0.59 0.64)
			(layers "B.Cu" "B.Mask" "B.Paste")
			(roundrect_rratio 0.25)
			(net 379 "/SFP/SH")
			(pintype "passive")
		)
	)
	(footprint "antmicro-footprints:TP_SMD_0.75mm"
		(layer "B.Cu")
		(at 233 89.2 180)
		(property "Reference" "TP20"
			(at -3 0.5 0)
			(layer "B.SilkS")
			(effects
				(font
					(size 0.7 0.7)
					(thickness 0.15)
				)
				(justify left bottom mirror)
			)
		)
		(property "Value" "TP_0.75mm_SMD"
			(at 0 -1.2 0)
			(layer "B.Fab")
			(effects
				(font
					(size 0.7 0.7)
					(thickness 0.15)
				)
				(justify left bottom mirror)
			)
		)
		(property "Description" "SMT test point"
			(at 0 0 0)
			(layer "B.Fab")
			(hide yes)
			(effects
				(font
					(size 1.27 1.27)
					(thickness 0.15)
				)
				(justify mirror)
			)
		)
		(property "MPN" ""
			(at 0 0 0)
			(unlocked yes)
			(layer "B.Fab")
			(hide yes)
			(effects
				(font
					(size 1 1)
					(thickness 0.15)
				)
				(justify mirror)
			)
		)
		(property "Manufacturer" ""
			(at 0 0 0)
			(unlocked yes)
			(layer "B.Fab")
			(hide yes)
			(effects
				(font
					(size 1 1)
					(thickness 0.15)
				)
				(justify mirror)
			)
		)
		(property "Author" "Antmicro"
			(at 0 0 0)
			(unlocked yes)
			(layer "B.Fab")
			(hide yes)
			(effects
				(font
					(size 1 1)
					(thickness 0.15)
				)
				(justify mirror)
			)
		)
		(property "License" "Apache-2.0"
			(at 0 0 0)
			(unlocked yes)
			(layer "B.Fab")
			(hide yes)
			(effects
				(font
					(size 1 1)
					(thickness 0.15)
				)
				(justify mirror)
			)
		)
		(sheetname "/USB DP Alt mode/")
		(sheetfile "usb_dp.kicad_sch")
		(attr exclude_from_pos_files exclude_from_bom)
		(fp_circle
			(center 0 0)
			(end 0.475 0)
			(stroke
				(width 0.05)
				(type default)
			)
			(fill no)
			(layer "B.CrtYd")
		)
		(fp_text user "${REFERENCE}"
			(at -0.4 -2.7 0)
			(layer "B.Fab")
			(effects
				(font
					(size 0.7 0.7)
					(thickness 0.15)
				)
				(justify left bottom mirror)
			)
		)
		(fp_text user "License: Apache-2.0"
			(at -0.4 -5.101 0)
			(layer "B.Fab")
			(effects
				(font
					(size 0.7 0.7)
					(thickness 0.15)
				)
				(justify left bottom mirror)
			)
		)
		(fp_text user "Author: Antmicro"
			(at -0.4 -3.901 0)
			(layer "B.Fab")
			(effects
				(font
					(size 0.7 0.7)
					(thickness 0.15)
				)
				(justify left bottom mirror)
			)
		)
		(pad "1" smd circle
			(at 0 0 180)
			(size 0.75 0.75)
			(layers "B.Cu" "B.Mask")
			(net 376 "/USB DP Alt mode/USBC1_VBUS")
			(pinfunction "1")
			(pintype "passive")
		)
	)
)
